FILE_TYPE = CONNECTIVITY;
{Allegro Design Entry HDL 17.2-2016 S081 (4005846) 1/11/2022}
"PAGE_NUMBER" = 69;
0"NC";
1"PVCCFA_EHV_FIVRA_CPU1\g";
2"PVCCFA_EHV_FIVRA_CPU1\g";
%"SOCKET4677_AZIF0045P001C01CS"
"30","(1300,2075)","0","pure_quanta","I1";
;
PART_NUMBER"DGA^7000023"
PART_TYPE"SMLF"
VALUE"SOCKET4677_AZIF0045-P001C01CS"
MATERIAL"IO"
$LOCATION"U1"
CDS_LIB"pure_quanta"
NEEDS_NO_SIZE"TRUE"
CDS_LMAN_SYM_OUTLINE"-1050,1500,1050,-1450"
CDS_LOCATION"U1"
$SEC"30"
CDS_SEC"30";
"VCCFA_EHV_FIVRA0"
$PN"AA11"1;
"VCCFA_EHV_FIVRA1"
$PN"AA15"1;
"VCCFA_EHV_FIVRA2"
$PN"AA7"1;
"VCCFA_EHV_FIVRA3"
$PN"AD85"1;
"VCCFA_EHV_FIVRA4"
$PN"AD89"1;
"VCCFA_EHV_FIVRA5"
$PN"AE11"1;
"VCCFA_EHV_FIVRA6"
$PN"AE15"1;
"VCCFA_EHV_FIVRA7"
$PN"AE7"1;
"VCCFA_EHV_FIVRA8"
$PN"AF77"1;
"VCCFA_EHV_FIVRA9"
$PN"AG78"1;
"VCCFA_EHV_FIVRA10"
$PN"AH85"1;
"VCCFA_EHV_FIVRA11"
$PN"AH89"1;
"VCCFA_EHV_FIVRA12"
$PN"AJ11"1;
"VCCFA_EHV_FIVRA13"
$PN"AJ15"1;
"VCCFA_EHV_FIVRA14"
$PN"AJ7"1;
"VCCFA_EHV_FIVRA15"
$PN"AM79"1;
"VCCFA_EHV_FIVRA16"
$PN"AM85"1;
"VCCFA_EHV_FIVRA17"
$PN"AM89"1;
"VCCFA_EHV_FIVRA18"
$PN"AN11"1;
"VCCFA_EHV_FIVRA19"
$PN"AN15"1;
"VCCFA_EHV_FIVRA20"
$PN"AN7"1;
"VCCFA_EHV_FIVRA21"
$PN"AN80"1;
"VCCFA_EHV_FIVRA22"
$PN"AT73"1;
"VCCFA_EHV_FIVRA23"
$PN"AT89"1;
"VCCFA_EHV_FIVRA24"
$PN"AU15"1;
"VCCFA_EHV_FIVRA25"
$PN"AW76"1;
"VCCFA_EHV_FIVRA26"
$PN"AY89"1;
"VCCFA_EHV_FIVRA27"
$PN"BE72"1;
"VCCFA_EHV_FIVRA28"
$PN"BF77"1;
"VCCFA_EHV_FIVRA29"
$PN"BH79"1;
"VCCFA_EHV_FIVRA30"
$PN"BJ72"1;
"VCCFA_EHV_FIVRA31"
$PN"BJ78"2;
"VCCFA_EHV_FIVRA32"
$PN"C84"1;
"VCCFA_EHV_FIVRA33"
$PN"C88"1;
"VCCFA_EHV_FIVRA34"
$PN"CE74"2;
"VCCFA_EHV_FIVRA35"
$PN"CK73"2;
"VCCFA_EHV_FIVRA36"
$PN"CK79"2;
"VCCFA_EHV_FIVRA37"
$PN"CM73"2;
"VCCFA_EHV_FIVRA38"
$PN"CN78"2;
"VCCFA_EHV_FIVRA39"
$PN"CP73"2;
"VCCFA_EHV_FIVRA40"
$PN"CT77"2;
"VCCFA_EHV_FIVRA41"
$PN"CT85"2;
"VCCFA_EHV_FIVRA42"
$PN"CY75"2;
"VCCFA_EHV_FIVRA43"
$PN"CY79"2;
"VCCFA_EHV_FIVRA44"
$PN"CY85"2;
"VCCFA_EHV_FIVRA45"
$PN"CY89"2;
"VCCFA_EHV_FIVRA46"
$PN"DD77"2;
"VCCFA_EHV_FIVRA47"
$PN"DD83"2;
"VCCFA_EHV_FIVRA48"
$PN"DD85"2;
"VCCFA_EHV_FIVRA49"
$PN"DD89"2;
"VCCFA_EHV_FIVRA50"
$PN"DH89"2;
"VCCFA_EHV_FIVRA51"
$PN"DM83"2;
"VCCFA_EHV_FIVRA52"
$PN"DM85"2;
"VCCFA_EHV_FIVRA53"
$PN"DM89"2;
"VCCFA_EHV_FIVRA54"
$PN"DN11"2;
"VCCFA_EHV_FIVRA55"
$PN"DN15"2;
"VCCFA_EHV_FIVRA56"
$PN"DN3"2;
"VCCFA_EHV_FIVRA57"
$PN"DN7"2;
"VCCFA_EHV_FIVRA58"
$PN"DT79"2;
"VCCFA_EHV_FIVRA59"
$PN"DT85"2;
"VCCFA_EHV_FIVRA60"
$PN"DT89"2;
"VCCFA_EHV_FIVRA61"
$PN"DU11"2;
"VCCFA_EHV_FIVRA62"
$PN"DU15"2;
"VCCFA_EHV_FIVRA63"
$PN"DU3"2;
"VCCFA_EHV_FIVRA64"
$PN"DU7"2;
"VCCFA_EHV_FIVRA65"
$PN"DY85"2;
"VCCFA_EHV_FIVRA66"
$PN"DY89"2;
"VCCFA_EHV_FIVRA67"
$PN"EA11"2;
"VCCFA_EHV_FIVRA68"
$PN"EA15"2;
"VCCFA_EHV_FIVRA69"
$PN"EA3"2;
"VCCFA_EHV_FIVRA70"
$PN"EA7"2;
"VCCFA_EHV_FIVRA71"
$PN"EC78"2;
"VCCFA_EHV_FIVRA72"
$PN"ED79"2;
"VCCFA_EHV_FIVRA73"
$PN"ED85"2;
"VCCFA_EHV_FIVRA74"
$PN"ED89"2;
"VCCFA_EHV_FIVRA75"
$PN"EE11"2;
"VCCFA_EHV_FIVRA76"
$PN"EE15"2;
"VCCFA_EHV_FIVRA77"
$PN"EE7"2;
"VCCFA_EHV_FIVRA78"
$PN"EE84"2;
"VCCFA_EHV_FIVRA79"
$PN"EF79"2;
"VCCFA_EHV_FIVRA80"
$PN"EG80"2;
"VCCFA_EHV_FIVRA81"
$PN"EJ15"2;
"VCCFA_EHV_FIVRA82"
$PN"EJ84"2;
"VCCFA_EHV_FIVRA83"
$PN"EN84"2;
"VCCFA_EHV_FIVRA84"
$PN"H89"1;
"VCCFA_EHV_FIVRA85"
$PN"J11"1;
"VCCFA_EHV_FIVRA86"
$PN"J7"1;
"VCCFA_EHV_FIVRA87"
$PN"J80"1;
"VCCFA_EHV_FIVRA88"
$PN"K87"1;
"VCCFA_EHV_FIVRA89"
$PN"L84"1;
"VCCFA_EHV_FIVRA90"
$PN"M85"1;
"VCCFA_EHV_FIVRA91"
$PN"M89"1;
"VCCFA_EHV_FIVRA92"
$PN"N11"1;
"VCCFA_EHV_FIVRA93"
$PN"N7"1;
"VCCFA_EHV_FIVRA94"
$PN"P79"1;
"VCCFA_EHV_FIVRA95"
$PN"R80"1;
"VCCFA_EHV_FIVRA96"
$PN"T85"1;
"VCCFA_EHV_FIVRA97"
$PN"T89"1;
"VCCFA_EHV_FIVRA98"
$PN"U11"1;
"VCCFA_EHV_FIVRA99"
$PN"U15"1;
"VCCFA_EHV_FIVRA100"
$PN"U7"1;
"VCCFA_EHV_FIVRA101"
$PN"W80"1;
"VCCFA_EHV_FIVRA102"
$PN"Y79"1;
"VCCFA_EHV_FIVRA103"
$PN"Y85"1;
"VCCFA_EHV_FIVRA104"
$PN"Y89"1;
%"VCC_CORE"
"1","(-150,4025)","0","logical_power","I2";
;
HDL_POWER"PVCCFA_EHV_FIVRA_CPU1"
CDS_LIB"logical_power";
"A"2;
%"VCC_CORE"
"1","(2750,4025)","0","logical_power","I3";
;
HDL_POWER"PVCCFA_EHV_FIVRA_CPU1"
CDS_LIB"logical_power";
"A"1;
END.
